(kicad_pcb
	(version 20260206)
	(generator "pcbnew")
	(generator_version "10.0")
	(general
		(thickness 1.6)
		(legacy_teardrops no)
	)
	(paper "A4")
	(title_block
		(title "01162023_DA0F0TEBIF0_F0T_Expander_BD_F_brd_V02_OCP.brd")
		(comment 1 "Grand Teton / footprints 1874-1880 of 9728")
	)
	(layers
		(0 "F.Cu" signal "TOP")
		(4 "In1.Cu" signal "GND")
		(6 "In2.Cu" signal "VCC")
		(8 "In3.Cu" signal "VCC1")
		(10 "In4.Cu" signal "GND1")
		(12 "In5.Cu" signal "IN1")
		(14 "In6.Cu" signal "GND2")
		(16 "In7.Cu" signal "IN2")
		(18 "In8.Cu" signal "GND3")
		(20 "In9.Cu" signal "IN3")
		(22 "In10.Cu" signal "GND4")
		(24 "In11.Cu" signal "IN4")
		(26 "In12.Cu" signal "GND5")
		(28 "In13.Cu" signal "IN5")
		(30 "In14.Cu" signal "GND6")
		(32 "In15.Cu" signal "IN6")
		(34 "In16.Cu" signal "GND7")
		(2 "B.Cu" signal "BOTTOM")
		(9 "F.Adhes" user "F.Adhesive")
		(11 "B.Adhes" user "B.Adhesive")
		(13 "F.Paste" user "Package Geometry/Pastemask Top")
		(15 "B.Paste" user "Package Geometry/Pastemask Bottom")
		(5 "F.SilkS" user "Ref Des/Silkscreen Top")
		(7 "B.SilkS" user "Ref Des/Silkscreen Bottom")
		(1 "F.Mask" user "Board Geometry/Soldermask Top")
		(3 "B.Mask" user "Board Geometry/Soldermask Bottom")
		(17 "Dwgs.User" user "User.Drawings")
		(19 "Cmts.User" user "User.Comments")
		(21 "Eco1.User" user "User.Eco1")
		(23 "Eco2.User" user "User.Eco2")
		(25 "Edge.Cuts" user "Board Geometry/Outline")
		(27 "Margin" user)
		(31 "F.CrtYd" user "Package Geometry/Place Bound Top")
		(29 "B.CrtYd" user "Package Geometry/Place Bound Bottom")
		(35 "F.Fab" user "Ref Des/Assembly Top")
		(33 "B.Fab" user "Ref Des/Assembly Bottom")
	)
	(footprint ""
		(layer "F.Cu")
		(at 173.689518 -63.56223)
		(property "Reference" "Q202"
			(at -0.004318 -1.8669 0)
			(unlocked yes)
			(layer "F.SilkS")
			(effects
				(font
					(size 0.7874 0.5842)
					(thickness 0.1524)
				)
			)
		)
		(property "Value" ""
			(at 0 0 0)
			(layer "F.Fab")
			(effects
				(font
					(size 1.27 1.27)
				)
			)
		)
		(duplicate_pad_numbers_are_jumpers no)
		(fp_line
			(start -1.376172 -1.199896)
			(end -0.508 -1.199896)
			(stroke
				(width 0.1524)
				(type default)
			)
			(layer "F.SilkS")
		)
		(fp_line
			(start -1.376172 1.199896)
			(end -1.376172 -1.199896)
			(stroke
				(width 0.1524)
				(type default)
			)
			(layer "F.SilkS")
		)
		(fp_line
			(start -0.508 -1.199896)
			(end 0 -0.762)
			(stroke
				(width 0.1524)
				(type default)
			)
			(layer "F.SilkS")
		)
		(fp_line
			(start 0 -0.762)
			(end 0.508 -1.199896)
			(stroke
				(width 0.1524)
				(type default)
			)
			(layer "F.SilkS")
		)
		(fp_line
			(start 0.508 -1.199896)
			(end 1.376172 -1.199896)
			(stroke
				(width 0.1524)
				(type default)
			)
			(layer "F.SilkS")
		)
		(fp_line
			(start 1.376172 -1.199896)
			(end 1.376172 1.199896)
			(stroke
				(width 0.1524)
				(type default)
			)
			(layer "F.SilkS")
		)
		(fp_line
			(start 1.376172 1.199896)
			(end -1.376172 1.199896)
			(stroke
				(width 0.1524)
				(type default)
			)
			(layer "F.SilkS")
		)
		(fp_poly
			(pts
				(xy -1.504696 -0.923544) (xy -1.773936 -1.731772) (xy -2.312924 -1.193038)
			)
			(stroke
				(width 0)
				(type default)
			)
			(fill yes)
			(layer "F.SilkS")
		)
		(fp_line
			(start -0.674878 -1.100074)
			(end 0.674878 -1.100074)
			(stroke
				(width 0.1)
				(type default)
			)
			(layer "F.Fab")
		)
		(fp_line
			(start -0.674878 1.100074)
			(end -0.674878 -1.100074)
			(stroke
				(width 0.1)
				(type default)
			)
			(layer "F.Fab")
		)
		(fp_line
			(start 0.674878 -1.100074)
			(end 0.674878 1.100074)
			(stroke
				(width 0.1)
				(type default)
			)
			(layer "F.Fab")
		)
		(fp_line
			(start 0.674878 1.100074)
			(end -0.674878 1.100074)
			(stroke
				(width 0.1)
				(type default)
			)
			(layer "F.Fab")
		)
		(fp_poly
			(pts
				(xy -1.4605 -0.7493) (xy -2.2225 -1.1303) (xy -2.2225 -0.3683)
			)
			(stroke
				(width 0)
				(type default)
			)
			(fill yes)
			(layer "F.Fab")
		)
		(pad "1" smd rect
			(at -0.899922 -0.750062 270)
			(size 0.6096 0.6096)
			(layers "F.Cu" "F.Mask" "F.Paste")
			(net "GND")
		)
		(pad "2" smd rect
			(at -0.899922 0 270)
			(size 0.4064 0.6096)
			(layers "F.Cu" "F.Mask" "F.Paste")
			(net "P12V_SSD6_PG_G1")
		)
		(pad "3" smd rect
			(at -0.899922 0.750062 270)
			(size 0.6096 0.6096)
			(layers "F.Cu" "F.Mask" "F.Paste")
			(net "PWRGD_P12V_SSD6_D")
		)
		(pad "4" smd rect
			(at 0.899922 0.750062 270)
			(size 0.6096 0.6096)
			(layers "F.Cu" "F.Mask" "F.Paste")
			(net "GND")
		)
		(pad "5" smd rect
			(at 0.899922 0 270)
			(size 0.4064 0.6096)
			(layers "F.Cu" "F.Mask" "F.Paste")
			(net "P12V_SSD6_PG_G2")
		)
		(pad "6" smd rect
			(at 0.899922 -0.750062 270)
			(size 0.6096 0.6096)
			(layers "F.Cu" "F.Mask" "F.Paste")
			(net "P12V_SSD6_PG_G2")
		)
	)
	(footprint ""
		(layer "F.Cu")
		(at 403.16658 -343.952322 90)
		(property "Reference" "C733"
			(at 0 0 90)
			(layer "F.SilkS")
			(hide yes)
			(effects
				(font
					(size 1.27 1.27)
				)
			)
		)
		(property "Value" ""
			(at 0 0 90)
			(layer "F.Fab")
			(effects
				(font
					(size 1.27 1.27)
				)
			)
		)
		(duplicate_pad_numbers_are_jumpers no)
		(fp_line
			(start 0.299974 -0.150114)
			(end 0.299974 0.150114)
			(stroke
				(width 0.1)
				(type default)
			)
			(layer "F.Fab")
		)
		(fp_line
			(start -0.299974 -0.150114)
			(end 0.299974 -0.150114)
			(stroke
				(width 0.1)
				(type default)
			)
			(layer "F.Fab")
		)
		(fp_line
			(start 0.299974 0.150114)
			(end -0.299974 0.150114)
			(stroke
				(width 0.1)
				(type default)
			)
			(layer "F.Fab")
		)
		(fp_line
			(start -0.299974 0.150114)
			(end -0.299974 -0.150114)
			(stroke
				(width 0.1)
				(type default)
			)
			(layer "F.Fab")
		)
		(pad "1" smd rect
			(at -0.2667 0 90)
			(size 0.3048 0.381)
			(layers "F.Cu" "F.Mask" "F.Paste")
			(net "P5E_PEX3_STN5_TX_DN<94>")
		)
		(pad "2" smd rect
			(at 0.2667 0 90)
			(size 0.3048 0.381)
			(layers "F.Cu" "F.Mask" "F.Paste")
			(net "P5E_PEX3_STN5_TX_C_DN<94>")
		)
	)
	(footprint ""
		(layer "F.Cu")
		(at 199.854312 -48.21809)
		(property "Reference" "PD67"
			(at 0 0 0)
			(layer "F.SilkS")
			(hide yes)
			(effects
				(font
					(size 1.27 1.27)
				)
			)
		)
		(property "Value" ""
			(at 0 0 0)
			(layer "F.Fab")
			(effects
				(font
					(size 1.27 1.27)
				)
			)
		)
		(duplicate_pad_numbers_are_jumpers no)
		(fp_line
			(start -3.400044 -1.459992)
			(end 4.107942 -1.459992)
			(stroke
				(width 0.1524)
				(type default)
			)
			(layer "F.SilkS")
		)
		(fp_line
			(start -3.400044 1.459992)
			(end -3.400044 -1.459992)
			(stroke
				(width 0.1524)
				(type default)
			)
			(layer "F.SilkS")
		)
		(fp_line
			(start 4.107942 -1.459992)
			(end 4.107942 1.459992)
			(stroke
				(width 0.1524)
				(type default)
			)
			(layer "F.SilkS")
		)
		(fp_line
			(start 4.107942 1.459992)
			(end -3.400044 1.459992)
			(stroke
				(width 0.1524)
				(type default)
			)
			(layer "F.SilkS")
		)
		(fp_poly
			(pts
				(xy 4.107942 -1.459992) (xy 4.107942 1.459992) (xy 3.308096 1.459992) (xy 3.308096 -1.459992)
			)
			(stroke
				(width 0)
				(type default)
			)
			(fill yes)
			(layer "F.SilkS")
		)
		(fp_line
			(start -2.29997 -1.459992)
			(end 2.29997 -1.459992)
			(stroke
				(width 0.1)
				(type default)
			)
			(layer "F.Fab")
		)
		(fp_line
			(start -2.29997 1.459992)
			(end -2.29997 -1.459992)
			(stroke
				(width 0.1)
				(type default)
			)
			(layer "F.Fab")
		)
		(fp_line
			(start 2.29997 -1.459992)
			(end 2.29997 1.459992)
			(stroke
				(width 0.1)
				(type default)
			)
			(layer "F.Fab")
		)
		(fp_line
			(start 2.29997 1.459992)
			(end -2.29997 1.459992)
			(stroke
				(width 0.1)
				(type default)
			)
			(layer "F.Fab")
		)
		(fp_text user "+"
			(at -4.7752 -0.12065 0)
			(unlocked yes)
			(layer "F.SilkS")
			(effects
				(font
					(size 1.905 1.4224)
					(thickness 0.1524)
				)
				(justify left)
			)
		)
		(fp_text user "-"
			(at 5.4102 0.29845 180)
			(unlocked yes)
			(layer "F.SilkS")
			(effects
				(font
					(size 1.905 1.4224)
					(thickness 0.1524)
				)
				(justify left)
			)
		)
		(fp_text user "+"
			(at -4.7752 -0.12065 0)
			(unlocked yes)
			(layer "F.Fab")
			(effects
				(font
					(size 1.905 1.4224)
					(thickness 0.1524)
				)
				(justify left)
			)
		)
		(fp_text user "-"
			(at 5.4102 0.29845 180)
			(unlocked yes)
			(layer "F.Fab")
			(effects
				(font
					(size 1.905 1.4224)
					(thickness 0.1524)
				)
				(justify left)
			)
		)
		(pad "A" smd rect
			(at -1.999996 0 90)
			(size 1.7018 2.5146)
			(layers "F.Cu" "F.Mask" "F.Paste")
			(net "GND")
		)
		(pad "C" smd rect
			(at 1.999996 0 90)
			(size 1.7018 2.5146)
			(layers "F.Cu" "F.Mask" "F.Paste")
			(net "P3V3_SSD7")
		)
	)
	(footprint ""
		(layer "F.Cu")
		(at 374.759474 -22.955504 90)
		(property "Reference" "R1727"
			(at 0 0 90)
			(layer "F.SilkS")
			(hide yes)
			(effects
				(font
					(size 1.27 1.27)
				)
			)
		)
		(property "Value" ""
			(at 0 0 90)
			(layer "F.Fab")
			(effects
				(font
					(size 1.27 1.27)
				)
			)
		)
		(duplicate_pad_numbers_are_jumpers no)
		(fp_line
			(start 0.7874 -0.4064)
			(end 0.7874 0.4064)
			(stroke
				(width 0.1524)
				(type default)
			)
			(layer "F.SilkS")
		)
		(fp_line
			(start -0.7874 -0.4064)
			(end 0.7874 -0.4064)
			(stroke
				(width 0.1524)
				(type default)
			)
			(layer "F.SilkS")
		)
		(fp_line
			(start 0.7874 0.4064)
			(end -0.7874 0.4064)
			(stroke
				(width 0.1524)
				(type default)
			)
			(layer "F.SilkS")
		)
		(fp_line
			(start -0.7874 0.4064)
			(end -0.7874 -0.4064)
			(stroke
				(width 0.1524)
				(type default)
			)
			(layer "F.SilkS")
		)
		(fp_line
			(start -0.12065 -0.305054)
			(end -0.12065 -0.2794)
			(stroke
				(width 0.1)
				(type default)
			)
			(layer "F.Fab")
		)
		(fp_line
			(start -0.67945 -0.305054)
			(end -0.12065 -0.305054)
			(stroke
				(width 0.1)
				(type default)
			)
			(layer "F.Fab")
		)
		(fp_line
			(start 0.67945 -0.3048)
			(end 0.67945 0.3048)
			(stroke
				(width 0.1)
				(type default)
			)
			(layer "F.Fab")
		)
		(fp_line
			(start 0.12065 -0.3048)
			(end 0.67945 -0.3048)
			(stroke
				(width 0.1)
				(type default)
			)
			(layer "F.Fab")
		)
		(fp_line
			(start 0.12065 -0.2794)
			(end 0.12065 -0.3048)
			(stroke
				(width 0.1)
				(type default)
			)
			(layer "F.Fab")
		)
		(fp_line
			(start -0.12065 -0.2794)
			(end 0.12065 -0.2794)
			(stroke
				(width 0.1)
				(type default)
			)
			(layer "F.Fab")
		)
		(fp_line
			(start 0.120396 0.2794)
			(end -0.12065 0.2794)
			(stroke
				(width 0.1)
				(type default)
			)
			(layer "F.Fab")
		)
		(fp_line
			(start -0.12065 0.2794)
			(end -0.12065 0.3048)
			(stroke
				(width 0.1)
				(type default)
			)
			(layer "F.Fab")
		)
		(fp_line
			(start 0.67945 0.3048)
			(end 0.120396 0.3048)
			(stroke
				(width 0.1)
				(type default)
			)
			(layer "F.Fab")
		)
		(fp_line
			(start 0.120396 0.3048)
			(end 0.120396 0.2794)
			(stroke
				(width 0.1)
				(type default)
			)
			(layer "F.Fab")
		)
		(fp_line
			(start -0.12065 0.3048)
			(end -0.67945 0.3048)
			(stroke
				(width 0.1)
				(type default)
			)
			(layer "F.Fab")
		)
		(fp_line
			(start -0.67945 0.3048)
			(end -0.67945 -0.305054)
			(stroke
				(width 0.1)
				(type default)
			)
			(layer "F.Fab")
		)
		(pad "1" smd circle
			(at -0.40005 0 90)
			(size 0 0)
			(layers "F.Cu" "F.Mask" "F.Paste")
			(net "SMB_BIC_I2C9_MUX1_SSD12_R_SCL")
		)
		(pad "2" smd circle
			(at 0.40005 0 90)
			(size 0 0)
			(layers "F.Cu" "F.Mask" "F.Paste")
			(net "SMB_ISO_SSD12_SCL")
		)
	)
	(footprint ""
		(layer "F.Cu")
		(at 250.651264 -114.914426 -90)
		(property "Reference" "PC901"
			(at 0 0 270)
			(layer "F.SilkS")
			(hide yes)
			(effects
				(font
					(size 1.27 1.27)
				)
			)
		)
		(property "Value" ""
			(at 0 0 270)
			(layer "F.Fab")
			(effects
				(font
					(size 1.27 1.27)
				)
			)
		)
		(duplicate_pad_numbers_are_jumpers no)
		(fp_line
			(start -1.524 0.762)
			(end -1.524 -0.762)
			(stroke
				(width 0.1524)
				(type default)
			)
			(layer "F.SilkS")
		)
		(fp_line
			(start 1.524 0.762)
			(end -1.524 0.762)
			(stroke
				(width 0.1524)
				(type default)
			)
			(layer "F.SilkS")
		)
		(fp_line
			(start -1.524 -0.762)
			(end 1.524 -0.762)
			(stroke
				(width 0.1524)
				(type default)
			)
			(layer "F.SilkS")
		)
		(fp_line
			(start 1.524 -0.762)
			(end 1.524 0.762)
			(stroke
				(width 0.1524)
				(type default)
			)
			(layer "F.SilkS")
		)
		(fp_line
			(start -1.1049 0.724916)
			(end 1.1049 0.724916)
			(stroke
				(width 0.1)
				(type default)
			)
			(layer "F.Fab")
		)
		(fp_line
			(start 1.1049 0.724916)
			(end 1.1049 -0.724916)
			(stroke
				(width 0.1)
				(type default)
			)
			(layer "F.Fab")
		)
		(fp_line
			(start -1.1049 -0.724916)
			(end -1.1049 0.724916)
			(stroke
				(width 0.1)
				(type default)
			)
			(layer "F.Fab")
		)
		(fp_line
			(start 1.1049 -0.724916)
			(end -1.1049 -0.724916)
			(stroke
				(width 0.1)
				(type default)
			)
			(layer "F.Fab")
		)
		(pad "1" smd rect
			(at -0.889 0 90)
			(size 1.016 1.27)
			(layers "F.Cu" "F.Mask" "F.Paste")
			(net "P3V3_NIC4")
		)
		(pad "2" smd rect
			(at 0.889 0 90)
			(size 1.016 1.27)
			(layers "F.Cu" "F.Mask" "F.Paste")
			(net "GND")
		)
	)
	(footprint ""
		(layer "F.Cu")
		(at 81.155032 -53.468524 90)
		(property "Reference" "PC499"
			(at 0 0 90)
			(layer "F.SilkS")
			(hide yes)
			(effects
				(font
					(size 1.27 1.27)
				)
			)
		)
		(property "Value" ""
			(at 0 0 90)
			(layer "F.Fab")
			(effects
				(font
					(size 1.27 1.27)
				)
			)
		)
		(duplicate_pad_numbers_are_jumpers no)
		(fp_line
			(start 1.524 -0.762)
			(end 1.524 0.762)
			(stroke
				(width 0.1524)
				(type default)
			)
			(layer "F.SilkS")
		)
		(fp_line
			(start -1.524 -0.762)
			(end 1.524 -0.762)
			(stroke
				(width 0.1524)
				(type default)
			)
			(layer "F.SilkS")
		)
		(fp_line
			(start 1.524 0.762)
			(end -1.524 0.762)
			(stroke
				(width 0.1524)
				(type default)
			)
			(layer "F.SilkS")
		)
		(fp_line
			(start -1.524 0.762)
			(end -1.524 -0.762)
			(stroke
				(width 0.1524)
				(type default)
			)
			(layer "F.SilkS")
		)
		(fp_line
			(start 1.1049 -0.724916)
			(end -1.1049 -0.724916)
			(stroke
				(width 0.1)
				(type default)
			)
			(layer "F.Fab")
		)
		(fp_line
			(start -1.1049 -0.724916)
			(end -1.1049 0.724916)
			(stroke
				(width 0.1)
				(type default)
			)
			(layer "F.Fab")
		)
		(fp_line
			(start 1.1049 0.724916)
			(end 1.1049 -0.724916)
			(stroke
				(width 0.1)
				(type default)
			)
			(layer "F.Fab")
		)
		(fp_line
			(start -1.1049 0.724916)
			(end 1.1049 0.724916)
			(stroke
				(width 0.1)
				(type default)
			)
			(layer "F.Fab")
		)
		(pad "1" smd rect
			(at -0.889 0 270)
			(size 1.016 1.27)
			(layers "F.Cu" "F.Mask" "F.Paste")
			(net "GND")
		)
		(pad "2" smd rect
			(at 0.889 0 270)
			(size 1.016 1.27)
			(layers "F.Cu" "F.Mask" "F.Paste")
			(net "P3V3_AUX")
		)
	)
	(footprint ""
		(layer "F.Cu")
		(at 133.63448 -308.648862 -90)
		(property "Reference" "C4263"
			(at 0 0 270)
			(layer "F.SilkS")
			(hide yes)
			(effects
				(font
					(size 1.27 1.27)
				)
			)
		)
		(property "Value" ""
			(at 0 0 270)
			(layer "F.Fab")
			(effects
				(font
					(size 1.27 1.27)
				)
			)
		)
		(duplicate_pad_numbers_are_jumpers no)
		(fp_line
			(start -1.2954 0.5842)
			(end -1.2954 -0.5842)
			(stroke
				(width 0.1524)
				(type default)
			)
			(layer "F.SilkS")
		)
		(fp_line
			(start 1.2954 0.5842)
			(end -1.2954 0.5842)
			(stroke
				(width 0.1524)
				(type default)
			)
			(layer "F.SilkS")
		)
		(fp_line
			(start -1.2954 -0.5842)
			(end 1.2954 -0.5842)
			(stroke
				(width 0.1524)
				(type default)
			)
			(layer "F.SilkS")
		)
		(fp_line
			(start 1.2954 -0.5842)
			(end 1.2954 0.5842)
			(stroke
				(width 0.1524)
				(type default)
			)
			(layer "F.SilkS")
		)
		(fp_line
			(start -0.8636 0.4572)
			(end -0.8636 0.4064)
			(stroke
				(width 0.1)
				(type default)
			)
			(layer "F.Fab")
		)
		(fp_line
			(start 0.8636 0.4572)
			(end -0.8636 0.4572)
			(stroke
				(width 0.1)
				(type default)
			)
			(layer "F.Fab")
		)
		(fp_line
			(start -1.1938 0.4064)
			(end -1.1938 -0.4064)
			(stroke
				(width 0.1)
				(type default)
			)
			(layer "F.Fab")
		)
		(fp_line
			(start -0.8636 0.4064)
			(end -1.1938 0.4064)
			(stroke
				(width 0.1)
				(type default)
			)
			(layer "F.Fab")
		)
		(fp_line
			(start 0.8636 0.4064)
			(end 0.8636 0.4572)
			(stroke
				(width 0.1)
				(type default)
			)
			(layer "F.Fab")
		)
		(fp_line
			(start 1.1938 0.4064)
			(end 0.8636 0.4064)
			(stroke
				(width 0.1)
				(type default)
			)
			(layer "F.Fab")
		)
		(fp_line
			(start -1.1938 -0.4064)
			(end -0.8636 -0.4064)
			(stroke
				(width 0.1)
				(type default)
			)
			(layer "F.Fab")
		)
		(fp_line
			(start -0.8636 -0.4064)
			(end -0.8636 -0.4572)
			(stroke
				(width 0.1)
				(type default)
			)
			(layer "F.Fab")
		)
		(fp_line
			(start 0.8636 -0.4064)
			(end 1.1938 -0.4064)
			(stroke
				(width 0.1)
				(type default)
			)
			(layer "F.Fab")
		)
		(fp_line
			(start 1.1938 -0.4064)
			(end 1.1938 0.4064)
			(stroke
				(width 0.1)
				(type default)
			)
			(layer "F.Fab")
		)
		(fp_line
			(start -0.8636 -0.4572)
			(end 0.8636 -0.4572)
			(stroke
				(width 0.1)
				(type default)
			)
			(layer "F.Fab")
		)
		(fp_line
			(start 0.8636 -0.4572)
			(end 0.8636 -0.4064)
			(stroke
				(width 0.1)
				(type default)
			)
			(layer "F.Fab")
		)
		(pad "1" smd rect
			(at -0.7366 0 180)
			(size 0.7112 0.8128)
			(layers "F.Cu" "F.Mask" "F.Paste")
			(net "P0V8_PEX1")
		)
		(pad "2" smd rect
			(at 0.7366 0 180)
			(size 0.7112 0.8128)
			(layers "F.Cu" "F.Mask" "F.Paste")
			(net "GND")
		)
	)
)
